# T6G (Grand Teton) — schematic netlist excerpt (pin names and nets, part order shuffled) for the footprints in the layout excerpt that follows; sources: Cadence DE-HDL packaged netlist, KiCad conversion of 04192023_DAF0TMB3IC0_F0TG_MB_C_brd_V02_OCP.brd

C327  Q_CAP  22UF 4V 20% X6S  pkg C0402  page 334 : A = P0V9_CPU1_RT_2D ; B = GND
R942  Q_RES  4.7K 5% CHIP  pkg 0402LF  page 34 : A = PVDD18_S5_P0 ; B = FM_BIOS_POST_CMPLT_N

(kicad_pcb
	(version 20260206)
	(generator "pcbnew")
	(generator_version "10.0")
	(general
		(thickness 1.6)
		(legacy_teardrops no)
	)
	(paper "A4")
	(title_block
		(title "04192023_DAF0TMB3IC0_F0TG_MB_C_brd_V02_OCP.brd")
		(comment 1 "Grand Teton / footprints 5282-5283 of 8354")
	)
	(layers
		(0 "F.Cu" signal "TOP")
		(4 "In1.Cu" signal "GND")
		(6 "In2.Cu" signal "IN1")
		(8 "In3.Cu" signal "GND1")
		(10 "In4.Cu" signal "IN2")
		(12 "In5.Cu" signal "GND2")
		(14 "In6.Cu" signal "IN3")
		(16 "In7.Cu" signal "GND3")
		(18 "In8.Cu" signal "VCC")
		(20 "In9.Cu" signal "VCC1")
		(22 "In10.Cu" signal "GND4")
		(24 "In11.Cu" signal "IN4")
		(26 "In12.Cu" signal "GND5")
		(28 "In13.Cu" signal "IN5")
		(30 "In14.Cu" signal "GND6")
		(32 "In15.Cu" signal "IN6")
		(34 "In16.Cu" signal "GND7")
		(2 "B.Cu" signal "BOTTOM")
		(9 "F.Adhes" user "F.Adhesive")
		(11 "B.Adhes" user "B.Adhesive")
		(13 "F.Paste" user "Package Geometry/Pastemask Top")
		(15 "B.Paste" user "Package Geometry/Pastemask Bottom")
		(5 "F.SilkS" user "Ref Des/Silkscreen Top")
		(7 "B.SilkS" user "Ref Des/Silkscreen Bottom")
		(1 "F.Mask" user "Board Geometry/Soldermask Top")
		(3 "B.Mask" user "Board Geometry/Soldermask Bottom")
		(17 "Dwgs.User" user "User.Drawings")
		(19 "Cmts.User" user "User.Comments")
		(21 "Eco1.User" user "User.Eco1")
		(23 "Eco2.User" user "User.Eco2")
		(25 "Edge.Cuts" user "Board Geometry/Outline")
		(27 "Margin" user)
		(31 "F.CrtYd" user "Package Geometry/Place Bound Top")
		(29 "B.CrtYd" user "Package Geometry/Place Bound Bottom")
		(35 "F.Fab" user "Ref Des/Assembly Top")
		(33 "B.Fab" user "Ref Des/Assembly Bottom")
	)
	(footprint ""
		(layer "B.Cu")
		(at 90.719148 -390.560052 90)
		(property "Reference" "C327"
			(at 0 0 90)
			(layer "B.SilkS")
			(hide yes)
			(effects
				(font
					(size 1.27 1.27)
				)
				(justify mirror)
			)
		)
		(property "Value" ""
			(at 0 0 90)
			(layer "B.Fab")
			(effects
				(font
					(size 1.27 1.27)
				)
				(justify mirror)
			)
		)
		(duplicate_pad_numbers_are_jumpers no)
		(fp_line
			(start 0.7874 -0.4064)
			(end -0.7874 -0.4064)
			(stroke
				(width 0.1524)
				(type default)
			)
			(layer "B.SilkS")
		)
		(fp_line
			(start -0.7874 -0.4064)
			(end -0.7874 0.4064)
			(stroke
				(width 0.1524)
				(type default)
			)
			(layer "B.SilkS")
		)
		(fp_line
			(start 0.7874 0.4064)
			(end 0.7874 -0.4064)
			(stroke
				(width 0.1524)
				(type default)
			)
			(layer "B.SilkS")
		)
		(fp_line
			(start -0.7874 0.4064)
			(end 0.7874 0.4064)
			(stroke
				(width 0.1524)
				(type default)
			)
			(layer "B.SilkS")
		)
		(fp_line
			(start 0.67945 -0.305054)
			(end 0.12065 -0.305054)
			(stroke
				(width 0.1)
				(type default)
			)
			(layer "B.Fab")
		)
		(fp_line
			(start 0.12065 -0.305054)
			(end 0.12065 -0.2794)
			(stroke
				(width 0.1)
				(type default)
			)
			(layer "B.Fab")
		)
		(fp_line
			(start -0.12065 -0.3048)
			(end -0.67945 -0.3048)
			(stroke
				(width 0.1)
				(type default)
			)
			(layer "B.Fab")
		)
		(fp_line
			(start -0.67945 -0.3048)
			(end -0.67945 0.3048)
			(stroke
				(width 0.1)
				(type default)
			)
			(layer "B.Fab")
		)
		(fp_line
			(start 0.12065 -0.2794)
			(end -0.12065 -0.2794)
			(stroke
				(width 0.1)
				(type default)
			)
			(layer "B.Fab")
		)
		(fp_line
			(start -0.12065 -0.2794)
			(end -0.12065 -0.3048)
			(stroke
				(width 0.1)
				(type default)
			)
			(layer "B.Fab")
		)
		(fp_line
			(start 0.12065 0.2794)
			(end 0.12065 0.3048)
			(stroke
				(width 0.1)
				(type default)
			)
			(layer "B.Fab")
		)
		(fp_line
			(start -0.120396 0.2794)
			(end 0.12065 0.2794)
			(stroke
				(width 0.1)
				(type default)
			)
			(layer "B.Fab")
		)
		(fp_line
			(start 0.67945 0.3048)
			(end 0.67945 -0.305054)
			(stroke
				(width 0.1)
				(type default)
			)
			(layer "B.Fab")
		)
		(fp_line
			(start 0.12065 0.3048)
			(end 0.67945 0.3048)
			(stroke
				(width 0.1)
				(type default)
			)
			(layer "B.Fab")
		)
		(fp_line
			(start -0.120396 0.3048)
			(end -0.120396 0.2794)
			(stroke
				(width 0.1)
				(type default)
			)
			(layer "B.Fab")
		)
		(fp_line
			(start -0.67945 0.3048)
			(end -0.120396 0.3048)
			(stroke
				(width 0.1)
				(type default)
			)
			(layer "B.Fab")
		)
		(pad "1" smd circle
			(at 0.40005 0 270)
			(size 0 0)
			(layers "B.Cu" "B.Mask" "B.Paste")
			(net "P0V9_CPU1_RT_2D")
		)
		(pad "2" smd circle
			(at -0.40005 0 270)
			(size 0 0)
			(layers "B.Cu" "B.Mask" "B.Paste")
			(net "GND")
		)
	)
	(footprint ""
		(layer "B.Cu")
		(at 397.637508 -341.168736 -90)
		(property "Reference" "R942"
			(at 0 0 90)
			(layer "B.SilkS")
			(hide yes)
			(effects
				(font
					(size 1.27 1.27)
				)
				(justify mirror)
			)
		)
		(property "Value" ""
			(at 0 0 90)
			(layer "B.Fab")
			(effects
				(font
					(size 1.27 1.27)
				)
				(justify mirror)
			)
		)
		(duplicate_pad_numbers_are_jumpers no)
		(fp_line
			(start -0.7874 0.4064)
			(end 0.7874 0.4064)
			(stroke
				(width 0.1524)
				(type default)
			)
			(layer "B.SilkS")
		)
		(fp_line
			(start 0.7874 0.4064)
			(end 0.7874 -0.4064)
			(stroke
				(width 0.1524)
				(type default)
			)
			(layer "B.SilkS")
		)
		(fp_line
			(start -0.7874 -0.4064)
			(end -0.7874 0.4064)
			(stroke
				(width 0.1524)
				(type default)
			)
			(layer "B.SilkS")
		)
		(fp_line
			(start 0.7874 -0.4064)
			(end -0.7874 -0.4064)
			(stroke
				(width 0.1524)
				(type default)
			)
			(layer "B.SilkS")
		)
		(fp_line
			(start -0.67945 0.3048)
			(end -0.120396 0.3048)
			(stroke
				(width 0.1)
				(type default)
			)
			(layer "B.Fab")
		)
		(fp_line
			(start -0.120396 0.3048)
			(end -0.120396 0.2794)
			(stroke
				(width 0.1)
				(type default)
			)
			(layer "B.Fab")
		)
		(fp_line
			(start 0.12065 0.3048)
			(end 0.67945 0.3048)
			(stroke
				(width 0.1)
				(type default)
			)
			(layer "B.Fab")
		)
		(fp_line
			(start 0.67945 0.3048)
			(end 0.67945 -0.305054)
			(stroke
				(width 0.1)
				(type default)
			)
			(layer "B.Fab")
		)
		(fp_line
			(start -0.120396 0.2794)
			(end 0.12065 0.2794)
			(stroke
				(width 0.1)
				(type default)
			)
			(layer "B.Fab")
		)
		(fp_line
			(start 0.12065 0.2794)
			(end 0.12065 0.3048)
			(stroke
				(width 0.1)
				(type default)
			)
			(layer "B.Fab")
		)
		(fp_line
			(start -0.12065 -0.2794)
			(end -0.12065 -0.3048)
			(stroke
				(width 0.1)
				(type default)
			)
			(layer "B.Fab")
		)
		(fp_line
			(start 0.12065 -0.2794)
			(end -0.12065 -0.2794)
			(stroke
				(width 0.1)
				(type default)
			)
			(layer "B.Fab")
		)
		(fp_line
			(start -0.67945 -0.3048)
			(end -0.67945 0.3048)
			(stroke
				(width 0.1)
				(type default)
			)
			(layer "B.Fab")
		)
		(fp_line
			(start -0.12065 -0.3048)
			(end -0.67945 -0.3048)
			(stroke
				(width 0.1)
				(type default)
			)
			(layer "B.Fab")
		)
		(fp_line
			(start 0.12065 -0.305054)
			(end 0.12065 -0.2794)
			(stroke
				(width 0.1)
				(type default)
			)
			(layer "B.Fab")
		)
		(fp_line
			(start 0.67945 -0.305054)
			(end 0.12065 -0.305054)
			(stroke
				(width 0.1)
				(type default)
			)
			(layer "B.Fab")
		)
		(pad "1" smd circle
			(at 0.40005 0 90)
			(size 0 0)
			(layers "B.Cu" "B.Mask" "B.Paste")
			(net "PVDD18_S5_P0")
		)
		(pad "2" smd circle
			(at -0.40005 0 90)
			(size 0 0)
			(layers "B.Cu" "B.Mask" "B.Paste")
			(net "FM_BIOS_POST_CMPLT_N")
		)
	)
)
